(kicad_pcb
	(version 20260206)
	(generator "pcbnew")
	(generator_version "10.0")
	(general
		(thickness 1.6)
		(legacy_teardrops no)
	)
	(paper "A4")
	(title_block
		(title "Wiwynn_Tioga_Pass_MB.brd")
		(comment 1 "Tioga Pass / footprints 4010-4016 of 4770")
	)
	(layers
		(0 "F.Cu" signal "TOP")
		(4 "In1.Cu" signal "L2GND")
		(6 "In2.Cu" signal "L3")
		(8 "In3.Cu" signal "L4GND")
		(10 "In4.Cu" signal "L5")
		(12 "In5.Cu" signal "L6GND")
		(14 "In6.Cu" signal "L7VCC")
		(16 "In7.Cu" signal "L8VCC")
		(18 "In8.Cu" signal "L9GND")
		(20 "In9.Cu" signal "L10")
		(22 "In10.Cu" signal "L11GND")
		(24 "In11.Cu" signal "L12")
		(26 "In12.Cu" signal "L13GND")
		(2 "B.Cu" signal "BOTTOM")
		(9 "F.Adhes" user "F.Adhesive")
		(11 "B.Adhes" user "B.Adhesive")
		(13 "F.Paste" user "Package Geometry/Pastemask Top")
		(15 "B.Paste" user "Package Geometry/Pastemask Bottom")
		(5 "F.SilkS" user "Ref Des/Silkscreen Top")
		(7 "B.SilkS" user "Ref Des/Silkscreen Bottom")
		(1 "F.Mask" user "Board Geometry/Soldermask Top")
		(3 "B.Mask" user "Board Geometry/Soldermask Bottom")
		(17 "Dwgs.User" user "User.Drawings")
		(19 "Cmts.User" user "User.Comments")
		(21 "Eco1.User" user "User.Eco1")
		(23 "Eco2.User" user "User.Eco2")
		(25 "Edge.Cuts" user "Board Geometry/Outline")
		(27 "Margin" user)
		(31 "F.CrtYd" user "Package Geometry/Place Bound Top")
		(29 "B.CrtYd" user "Package Geometry/Place Bound Bottom")
		(35 "F.Fab" user "Ref Des/Assembly Top")
		(33 "B.Fab" user "Ref Des/Assembly Bottom")
	)
	(footprint ""
		(layer "B.Cu")
		(at 456.4888 -52.483258)
		(property "Reference" "C1R6"
			(at 0 0 0)
			(layer "B.SilkS")
			(hide yes)
			(effects
				(font
					(size 1.27 1.27)
				)
				(justify mirror)
			)
		)
		(property "Value" ""
			(at 0 0 0)
			(layer "B.Fab")
			(effects
				(font
					(size 1.27 1.27)
				)
				(justify mirror)
			)
		)
		(duplicate_pad_numbers_are_jumpers no)
		(fp_poly
			(pts
				(xy -0.3048 -0.1016) (xy -0.3048 0.9906) (xy 0.3048 0.9906) (xy 0.3048 -0.1016)
			)
			(stroke
				(width 0)
				(type default)
			)
			(fill no)
			(layer "B.CrtYd")
		)
		(fp_line
			(start -0.3048 -0.1016)
			(end 0.3048 -0.1016)
			(stroke
				(width 0.1)
				(type default)
			)
			(layer "B.Fab")
		)
		(fp_line
			(start -0.3048 0.9906)
			(end -0.3048 -0.1016)
			(stroke
				(width 0.1)
				(type default)
			)
			(layer "B.Fab")
		)
		(fp_line
			(start 0.3048 -0.1016)
			(end 0.3048 0.9906)
			(stroke
				(width 0.1)
				(type default)
			)
			(layer "B.Fab")
		)
		(fp_line
			(start 0.3048 0.9906)
			(end -0.3048 0.9906)
			(stroke
				(width 0.1)
				(type default)
			)
			(layer "B.Fab")
		)
		(pad "1" smd rect
			(at 0 0 180)
			(size 0.508 0.508)
			(layers "B.Cu" "B.Mask" "B.Paste")
			(net "P3E_CPU0_PE3_OCP_TXP<2>")
		)
		(pad "2" smd rect
			(at 0 0.889 180)
			(size 0.508 0.508)
			(layers "B.Cu" "B.Mask" "B.Paste")
			(net "P3E_OCP_CPU0_PE3_C_TXP<2>")
		)
		(zone
			(layer "B.Cu")
			(hatch none 0.5)
			(connect_pads
				(clearance 0)
			)
			(min_thickness 0.25)
			(keepout
				(tracks allowed)
				(vias not_allowed)
				(pads allowed)
				(copperpour not_allowed)
				(footprints allowed)
			)
			(placement
				(enabled no)
				(sheetname "")
			)
			(fill
				(thermal_gap 0.5)
				(thermal_bridge_width 0.5)
				(island_removal_mode 0)
			)
			(polygon
				(pts
					(xy 456.7428 -52.229258) (xy 456.2348 -52.229258) (xy 456.2348 -51.848258) (xy 456.7428 -51.848258)
				)
			)
		)
	)
	(footprint ""
		(layer "B.Cu")
		(at 460.4512 -129.6924 90)
		(property "Reference" "U1M4"
			(at -0.34036 2.28473 270)
			(unlocked yes)
			(layer "B.SilkS")
			(effects
				(font
					(size 0.7874 0.5842)
					(thickness 0.1524)
				)
				(justify left mirror)
			)
		)
		(property "Value" ""
			(at 0 0 90)
			(layer "B.Fab")
			(effects
				(font
					(size 1.27 1.27)
				)
				(justify mirror)
			)
		)
		(duplicate_pad_numbers_are_jumpers no)
		(fp_circle
			(center 0.858012 -0.008636)
			(end 0.858012 0.118364)
			(stroke
				(width 0.254)
				(type default)
			)
			(fill no)
			(layer "B.SilkS")
		)
		(fp_poly
			(pts
				(xy -0.21463 -0.450088) (xy -1.56337 -0.450088) (xy -1.56337 1.75006) (xy -0.21463 1.75006)
			)
			(stroke
				(width 0)
				(type default)
			)
			(fill no)
			(layer "B.CrtYd")
		)
		(fp_line
			(start -0.21463 -0.450088)
			(end -1.56337 -0.450088)
			(stroke
				(width 0.1)
				(type default)
			)
			(layer "B.Fab")
		)
		(fp_line
			(start -1.56337 -0.450088)
			(end -1.56337 1.75006)
			(stroke
				(width 0.1)
				(type default)
			)
			(layer "B.Fab")
		)
		(fp_line
			(start -0.21463 1.75006)
			(end -0.21463 -0.450088)
			(stroke
				(width 0.1)
				(type default)
			)
			(layer "B.Fab")
		)
		(fp_line
			(start -1.56337 1.75006)
			(end -0.21463 1.75006)
			(stroke
				(width 0.1)
				(type default)
			)
			(layer "B.Fab")
		)
		(fp_circle
			(center 0.4699 -0.8382)
			(end 0.4699 -0.7112)
			(stroke
				(width 0.254)
				(type default)
			)
			(fill no)
			(layer "B.Fab")
		)
		(pad "1" smd rect
			(at 0 0 270)
			(size 1.016 0.381)
			(layers "B.Cu" "B.Mask" "B.Paste")
			(net "FM_CPU1_SKTOCC_LVT3_N")
		)
		(pad "2" smd rect
			(at 0 0.649986 270)
			(size 1.016 0.381)
			(layers "B.Cu" "B.Mask" "B.Paste")
			(net "XDP_CPU0_TDO")
		)
		(pad "3" smd rect
			(at 0 1.299972 270)
			(size 1.016 0.381)
			(layers "B.Cu" "B.Mask" "B.Paste")
			(net "GND")
		)
		(pad "4" smd rect
			(at -1.778 1.299972 270)
			(size 1.016 0.381)
			(layers "B.Cu" "B.Mask" "B.Paste")
			(net "XDP_CPU1_TDI")
		)
		(pad "5" smd rect
			(at -1.778 0 270)
			(size 1.016 0.381)
			(layers "B.Cu" "B.Mask" "B.Paste")
			(net "P3V3_STBY")
		)
	)
	(footprint ""
		(layer "B.Cu")
		(at 486.119424 -58.104024 90)
		(property "Reference" "R30W2"
			(at 0.8382 -0.67818 90)
			(unlocked yes)
			(layer "B.SilkS")
			(effects
				(font
					(size 0.4064 0.254)
					(thickness 0.1524)
				)
				(justify left mirror)
			)
		)
		(property "Value" ""
			(at 0 0 90)
			(layer "B.Fab")
			(effects
				(font
					(size 1.27 1.27)
				)
				(justify mirror)
			)
		)
		(duplicate_pad_numbers_are_jumpers no)
		(fp_poly
			(pts
				(xy 0.2794 -0.1016) (xy -0.2794 -0.1016) (xy -0.2794 0.9906) (xy 0.2794 0.9906)
			)
			(stroke
				(width 0)
				(type default)
			)
			(fill no)
			(layer "B.CrtYd")
		)
		(fp_line
			(start 0.2794 -0.1016)
			(end 0.2794 0.9906)
			(stroke
				(width 0.1)
				(type default)
			)
			(layer "B.Fab")
		)
		(fp_line
			(start -0.2794 -0.1016)
			(end 0.2794 -0.1016)
			(stroke
				(width 0.1)
				(type default)
			)
			(layer "B.Fab")
		)
		(fp_line
			(start 0.2794 0.9906)
			(end -0.2794 0.9906)
			(stroke
				(width 0.1)
				(type default)
			)
			(layer "B.Fab")
		)
		(fp_line
			(start -0.2794 0.9906)
			(end -0.2794 -0.1016)
			(stroke
				(width 0.1)
				(type default)
			)
			(layer "B.Fab")
		)
		(pad "1" smd rect
			(at 0 0 270)
			(size 0.508 0.508)
			(layers "B.Cu" "B.Mask" "B.Paste")
			(net "USB3_P01_RXP")
		)
		(pad "2" smd rect
			(at 0 0.889 270)
			(size 0.508 0.508)
			(layers "B.Cu" "B.Mask" "B.Paste")
			(net "USB3_P01_FB_RXP")
		)
		(zone
			(layer "B.Cu")
			(hatch none 0.5)
			(connect_pads
				(clearance 0)
			)
			(min_thickness 0.25)
			(keepout
				(tracks allowed)
				(vias not_allowed)
				(pads allowed)
				(copperpour not_allowed)
				(footprints allowed)
			)
			(placement
				(enabled no)
				(sheetname "")
			)
			(fill
				(thermal_gap 0.5)
				(thermal_bridge_width 0.5)
				(island_removal_mode 0)
			)
			(polygon
				(pts
					(xy 486.373424 -58.358024) (xy 486.373424 -57.850024) (xy 486.754424 -57.850024) (xy 486.754424 -58.358024)
				)
			)
		)
		(zone
			(layer "B.Cu")
			(hatch none 0.5)
			(connect_pads
				(clearance 0)
			)
			(min_thickness 0.25)
			(keepout
				(tracks not_allowed)
				(vias allowed)
				(pads allowed)
				(copperpour not_allowed)
				(footprints allowed)
			)
			(placement
				(enabled no)
				(sheetname "")
			)
			(fill
				(thermal_gap 0.5)
				(thermal_bridge_width 0.5)
				(island_removal_mode 0)
			)
			(polygon
				(pts
					(xy 486.754424 -58.358024) (xy 486.754424 -57.850024) (xy 486.373424 -57.850024) (xy 486.373424 -58.358024)
				)
			)
		)
	)
	(footprint ""
		(layer "B.Cu")
		(at 94.300548 -135.376412 90)
		(property "Reference" "C8M7"
			(at 0 0 90)
			(layer "B.SilkS")
			(hide yes)
			(effects
				(font
					(size 1.27 1.27)
				)
				(justify mirror)
			)
		)
		(property "Value" ""
			(at 0 0 90)
			(layer "B.Fab")
			(effects
				(font
					(size 1.27 1.27)
				)
				(justify mirror)
			)
		)
		(duplicate_pad_numbers_are_jumpers no)
		(fp_poly
			(pts
				(xy 0.7239 -0.2159) (xy -0.7239 -0.2159) (xy -0.7239 1.9939) (xy 0.7239 1.9939)
			)
			(stroke
				(width 0)
				(type default)
			)
			(fill no)
			(layer "B.CrtYd")
		)
		(fp_line
			(start 0.7239 -0.2159)
			(end 0.7239 1.9939)
			(stroke
				(width 0.1)
				(type default)
			)
			(layer "B.Fab")
		)
		(fp_line
			(start -0.7239 -0.2159)
			(end 0.7239 -0.2159)
			(stroke
				(width 0.1)
				(type default)
			)
			(layer "B.Fab")
		)
		(fp_line
			(start 0.7239 1.9939)
			(end -0.7239 1.9939)
			(stroke
				(width 0.1)
				(type default)
			)
			(layer "B.Fab")
		)
		(fp_line
			(start -0.7239 1.9939)
			(end -0.7239 -0.2159)
			(stroke
				(width 0.1)
				(type default)
			)
			(layer "B.Fab")
		)
		(pad "1" smd rect
			(at 0 0 270)
			(size 1.27 1.016)
			(layers "B.Cu" "B.Mask" "B.Paste")
			(net "PVDDQ_KLM")
		)
		(pad "2" smd rect
			(at 0 1.778 270)
			(size 1.27 1.016)
			(layers "B.Cu" "B.Mask" "B.Paste")
			(net "GND")
		)
		(zone
			(layer "B.Cu")
			(hatch none 0.5)
			(connect_pads
				(clearance 0)
			)
			(min_thickness 0.25)
			(keepout
				(tracks not_allowed)
				(vias allowed)
				(pads allowed)
				(copperpour not_allowed)
				(footprints allowed)
			)
			(placement
				(enabled no)
				(sheetname "")
			)
			(fill
				(thermal_gap 0.5)
				(thermal_bridge_width 0.5)
				(island_removal_mode 0)
			)
			(polygon
				(pts
					(xy 94.808548 -136.011412) (xy 94.808548 -134.741412) (xy 95.570548 -134.741412) (xy 95.570548 -136.011412)
				)
			)
		)
	)
	(footprint ""
		(layer "B.Cu")
		(at 487.62412 -60.016644 180)
		(property "Reference" "L30W2"
			(at -0.127 -1.07188 180)
			(unlocked yes)
			(layer "B.SilkS")
			(effects
				(font
					(size 0.4064 0.254)
					(thickness 0.1524)
				)
				(justify left mirror)
			)
		)
		(property "Value" ""
			(at 0 0 0)
			(layer "B.Fab")
			(effects
				(font
					(size 1.27 1.27)
				)
				(justify mirror)
			)
		)
		(duplicate_pad_numbers_are_jumpers no)
		(fp_rect
			(start 0.08382 1.09982)
			(end -2.11582 -0.29972)
			(stroke
				(width 0)
				(type default)
			)
			(fill no)
			(layer "B.CrtYd")
		)
		(fp_line
			(start 0.08382 1.09982)
			(end 0.08382 -0.29972)
			(stroke
				(width 0.1)
				(type default)
			)
			(layer "B.Fab")
		)
		(fp_line
			(start 0.08382 -0.29972)
			(end -2.11582 -0.29972)
			(stroke
				(width 0.1)
				(type default)
			)
			(layer "B.Fab")
		)
		(fp_line
			(start -2.11582 1.09982)
			(end 0.08382 1.09982)
			(stroke
				(width 0.1)
				(type default)
			)
			(layer "B.Fab")
		)
		(fp_line
			(start -2.11582 -0.29972)
			(end -2.11582 1.09982)
			(stroke
				(width 0.1)
				(type default)
			)
			(layer "B.Fab")
		)
		(pad "1" smd rect
			(at 0 0)
			(size 1.27 0.508)
			(layers "B.Cu" "B.Mask" "B.Paste")
			(net "USB3_P01_C_TXP")
		)
		(pad "2" smd rect
			(at -2.032 0)
			(size 1.27 0.508)
			(layers "B.Cu" "B.Mask" "B.Paste")
			(net "USB3_P01_FB_TXP")
		)
		(pad "3" smd rect
			(at -2.032 0.8001)
			(size 1.27 0.508)
			(layers "B.Cu" "B.Mask" "B.Paste")
			(net "USB3_P01_FB_TXN")
		)
		(pad "4" smd rect
			(at 0 0.8001)
			(size 1.27 0.508)
			(layers "B.Cu" "B.Mask" "B.Paste")
			(net "USB3_P01_C_TXN")
		)
		(zone
			(layer "B.Cu")
			(hatch none 0.5)
			(connect_pads
				(clearance 0)
			)
			(min_thickness 0.25)
			(keepout
				(tracks not_allowed)
				(vias allowed)
				(pads allowed)
				(copperpour not_allowed)
				(footprints allowed)
			)
			(placement
				(enabled no)
				(sheetname "")
			)
			(fill
				(thermal_gap 0.5)
				(thermal_bridge_width 0.5)
				(island_removal_mode 0)
			)
			(polygon
				(pts
					(xy 486.98912 -60.562744) (xy 486.98912 -60.270644) (xy 488.25912 -60.270644) (xy 488.25912 -60.562744)
				)
			)
		)
		(zone
			(layer "B.Cu")
			(hatch none 0.5)
			(connect_pads
				(clearance 0)
			)
			(min_thickness 0.25)
			(keepout
				(tracks not_allowed)
				(vias allowed)
				(pads allowed)
				(copperpour not_allowed)
				(footprints allowed)
			)
			(placement
				(enabled no)
				(sheetname "")
			)
			(fill
				(thermal_gap 0.5)
				(thermal_bridge_width 0.5)
				(island_removal_mode 0)
			)
			(polygon
				(pts
					(xy 488.25912 -61.070744) (xy 489.02112 -61.070744) (xy 489.02112 -59.762644) (xy 488.25912 -59.762644)
				)
			)
		)
		(zone
			(layer "B.Cu")
			(hatch none 0.5)
			(connect_pads
				(clearance 0)
			)
			(min_thickness 0.25)
			(keepout
				(tracks allowed)
				(vias not_allowed)
				(pads allowed)
				(copperpour not_allowed)
				(footprints allowed)
			)
			(placement
				(enabled no)
				(sheetname "")
			)
			(fill
				(thermal_gap 0.5)
				(thermal_bridge_width 0.5)
				(island_removal_mode 0)
			)
			(polygon
				(pts
					(xy 488.25912 -59.762644) (xy 488.25912 -61.070744) (xy 489.02112 -61.070744) (xy 489.02112 -59.762644)
				)
			)
		)
		(zone
			(layer "B.Cu")
			(hatch none 0.5)
			(connect_pads
				(clearance 0)
			)
			(min_thickness 0.25)
			(keepout
				(tracks not_allowed)
				(vias allowed)
				(pads allowed)
				(copperpour not_allowed)
				(footprints allowed)
			)
			(placement
				(enabled no)
				(sheetname "")
			)
			(fill
				(thermal_gap 0.5)
				(thermal_bridge_width 0.5)
				(island_removal_mode 0)
			)
			(polygon
				(pts
					(xy 489.02112 -60.562744) (xy 489.02112 -60.270644) (xy 490.29112 -60.270644) (xy 490.29112 -60.562744)
				)
			)
		)
	)
	(footprint ""
		(layer "B.Cu")
		(at 465.595208 -147.066254)
		(property "Reference" "R1L17"
			(at 0 0 0)
			(layer "B.SilkS")
			(hide yes)
			(effects
				(font
					(size 1.27 1.27)
				)
				(justify mirror)
			)
		)
		(property "Value" ""
			(at 0 0 0)
			(layer "B.Fab")
			(effects
				(font
					(size 1.27 1.27)
				)
				(justify mirror)
			)
		)
		(duplicate_pad_numbers_are_jumpers no)
		(fp_poly
			(pts
				(xy 0.2794 -0.1016) (xy -0.2794 -0.1016) (xy -0.2794 0.9906) (xy 0.2794 0.9906)
			)
			(stroke
				(width 0)
				(type default)
			)
			(fill no)
			(layer "B.CrtYd")
		)
		(fp_line
			(start -0.2794 -0.1016)
			(end 0.2794 -0.1016)
			(stroke
				(width 0.1)
				(type default)
			)
			(layer "B.Fab")
		)
		(fp_line
			(start -0.2794 0.9906)
			(end -0.2794 -0.1016)
			(stroke
				(width 0.1)
				(type default)
			)
			(layer "B.Fab")
		)
		(fp_line
			(start 0.2794 -0.1016)
			(end 0.2794 0.9906)
			(stroke
				(width 0.1)
				(type default)
			)
			(layer "B.Fab")
		)
		(fp_line
			(start 0.2794 0.9906)
			(end -0.2794 0.9906)
			(stroke
				(width 0.1)
				(type default)
			)
			(layer "B.Fab")
		)
		(pad "1" smd rect
			(at 0 0 180)
			(size 0.508 0.508)
			(layers "B.Cu" "B.Mask" "B.Paste")
			(net "XDP_CPU_PWR_DEBUG_N")
		)
		(pad "2" smd rect
			(at 0 0.889 180)
			(size 0.508 0.508)
			(layers "B.Cu" "B.Mask" "B.Paste")
			(net "PVCCIO_CPU0")
		)
		(zone
			(layer "B.Cu")
			(hatch none 0.5)
			(connect_pads
				(clearance 0)
			)
			(min_thickness 0.25)
			(keepout
				(tracks allowed)
				(vias not_allowed)
				(pads allowed)
				(copperpour not_allowed)
				(footprints allowed)
			)
			(placement
				(enabled no)
				(sheetname "")
			)
			(fill
				(thermal_gap 0.5)
				(thermal_bridge_width 0.5)
				(island_removal_mode 0)
			)
			(polygon
				(pts
					(xy 465.849208 -146.812254) (xy 465.341208 -146.812254) (xy 465.341208 -146.431254) (xy 465.849208 -146.431254)
				)
			)
		)
		(zone
			(layer "B.Cu")
			(hatch none 0.5)
			(connect_pads
				(clearance 0)
			)
			(min_thickness 0.25)
			(keepout
				(tracks not_allowed)
				(vias allowed)
				(pads allowed)
				(copperpour not_allowed)
				(footprints allowed)
			)
			(placement
				(enabled no)
				(sheetname "")
			)
			(fill
				(thermal_gap 0.5)
				(thermal_bridge_width 0.5)
				(island_removal_mode 0)
			)
			(polygon
				(pts
					(xy 465.849208 -146.431254) (xy 465.341208 -146.431254) (xy 465.341208 -146.812254) (xy 465.849208 -146.812254)
				)
			)
		)
	)
	(footprint ""
		(layer "B.Cu")
		(at 260.923024 -82.001614)
		(property "Reference" "C5P8"
			(at 0 0 0)
			(layer "B.SilkS")
			(hide yes)
			(effects
				(font
					(size 1.27 1.27)
				)
				(justify mirror)
			)
		)
		(property "Value" ""
			(at 0 0 0)
			(layer "B.Fab")
			(effects
				(font
					(size 1.27 1.27)
				)
				(justify mirror)
			)
		)
		(duplicate_pad_numbers_are_jumpers no)
		(fp_poly
			(pts
				(xy 0.7239 -0.2159) (xy -0.7239 -0.2159) (xy -0.7239 1.9939) (xy 0.7239 1.9939)
			)
			(stroke
				(width 0)
				(type default)
			)
			(fill no)
			(layer "B.CrtYd")
		)
		(fp_line
			(start -0.7239 -0.2159)
			(end 0.7239 -0.2159)
			(stroke
				(width 0.1)
				(type default)
			)
			(layer "B.Fab")
		)
		(fp_line
			(start -0.7239 1.9939)
			(end -0.7239 -0.2159)
			(stroke
				(width 0.1)
				(type default)
			)
			(layer "B.Fab")
		)
		(fp_line
			(start 0.7239 -0.2159)
			(end 0.7239 1.9939)
			(stroke
				(width 0.1)
				(type default)
			)
			(layer "B.Fab")
		)
		(fp_line
			(start 0.7239 1.9939)
			(end -0.7239 1.9939)
			(stroke
				(width 0.1)
				(type default)
			)
			(layer "B.Fab")
		)
		(pad "1" smd rect
			(at 0 0 180)
			(size 1.27 1.016)
			(layers "B.Cu" "B.Mask" "B.Paste")
			(net "PVSA_CPU0")
		)
		(pad "2" smd rect
			(at 0 1.778 180)
			(size 1.27 1.016)
			(layers "B.Cu" "B.Mask" "B.Paste")
			(net "GND")
		)
		(zone
			(layer "B.Cu")
			(hatch none 0.5)
			(connect_pads
				(clearance 0)
			)
			(min_thickness 0.25)
			(keepout
				(tracks not_allowed)
				(vias allowed)
				(pads allowed)
				(copperpour not_allowed)
				(footprints allowed)
			)
			(placement
				(enabled no)
				(sheetname "")
			)
			(fill
				(thermal_gap 0.5)
				(thermal_bridge_width 0.5)
				(island_removal_mode 0)
			)
			(polygon
				(pts
					(xy 261.558024 -81.493614) (xy 260.288024 -81.493614) (xy 260.288024 -80.731614) (xy 261.558024 -80.731614)
				)
			)
		)
	)
)
